(kicad_pcb
	(version 20260206)
	(generator "pcbnew")
	(generator_version "10.0")
	(general
		(thickness 1.6)
		(legacy_teardrops no)
	)
	(paper "A4")
	(title_block
		(title "01162023_DA0F0TEBIF0_F0T_Expander_BD_F_brd_V02_OCP.brd")
		(comment 1 "Grand Teton / footprints 1703-1708 of 9728")
	)
	(layers
		(0 "F.Cu" signal "TOP")
		(4 "In1.Cu" signal "GND")
		(6 "In2.Cu" signal "VCC")
		(8 "In3.Cu" signal "VCC1")
		(10 "In4.Cu" signal "GND1")
		(12 "In5.Cu" signal "IN1")
		(14 "In6.Cu" signal "GND2")
		(16 "In7.Cu" signal "IN2")
		(18 "In8.Cu" signal "GND3")
		(20 "In9.Cu" signal "IN3")
		(22 "In10.Cu" signal "GND4")
		(24 "In11.Cu" signal "IN4")
		(26 "In12.Cu" signal "GND5")
		(28 "In13.Cu" signal "IN5")
		(30 "In14.Cu" signal "GND6")
		(32 "In15.Cu" signal "IN6")
		(34 "In16.Cu" signal "GND7")
		(2 "B.Cu" signal "BOTTOM")
		(9 "F.Adhes" user "F.Adhesive")
		(11 "B.Adhes" user "B.Adhesive")
		(13 "F.Paste" user "Package Geometry/Pastemask Top")
		(15 "B.Paste" user "Package Geometry/Pastemask Bottom")
		(5 "F.SilkS" user "Ref Des/Silkscreen Top")
		(7 "B.SilkS" user "Ref Des/Silkscreen Bottom")
		(1 "F.Mask" user "Board Geometry/Soldermask Top")
		(3 "B.Mask" user "Board Geometry/Soldermask Bottom")
		(17 "Dwgs.User" user "User.Drawings")
		(19 "Cmts.User" user "User.Comments")
		(21 "Eco1.User" user "User.Eco1")
		(23 "Eco2.User" user "User.Eco2")
		(25 "Edge.Cuts" user "Board Geometry/Outline")
		(27 "Margin" user)
		(31 "F.CrtYd" user "Package Geometry/Place Bound Top")
		(29 "B.CrtYd" user "Package Geometry/Place Bound Bottom")
		(35 "F.Fab" user "Ref Des/Assembly Top")
		(33 "B.Fab" user "Ref Des/Assembly Bottom")
	)
	(footprint ""
		(layer "F.Cu")
		(at 458.452982 -116.230654 90)
		(property "Reference" "PR7058"
			(at 0 0 90)
			(layer "F.SilkS")
			(hide yes)
			(effects
				(font
					(size 1.27 1.27)
				)
			)
		)
		(property "Value" ""
			(at 0 0 90)
			(layer "F.Fab")
			(effects
				(font
					(size 1.27 1.27)
				)
			)
		)
		(duplicate_pad_numbers_are_jumpers no)
		(fp_line
			(start 0.7874 -0.4064)
			(end 0.7874 0.4064)
			(stroke
				(width 0.1524)
				(type default)
			)
			(layer "F.SilkS")
		)
		(fp_line
			(start -0.7874 -0.4064)
			(end 0.7874 -0.4064)
			(stroke
				(width 0.1524)
				(type default)
			)
			(layer "F.SilkS")
		)
		(fp_line
			(start 0.7874 0.4064)
			(end -0.7874 0.4064)
			(stroke
				(width 0.1524)
				(type default)
			)
			(layer "F.SilkS")
		)
		(fp_line
			(start -0.7874 0.4064)
			(end -0.7874 -0.4064)
			(stroke
				(width 0.1524)
				(type default)
			)
			(layer "F.SilkS")
		)
		(fp_line
			(start -0.12065 -0.305054)
			(end -0.12065 -0.2794)
			(stroke
				(width 0.1)
				(type default)
			)
			(layer "F.Fab")
		)
		(fp_line
			(start -0.67945 -0.305054)
			(end -0.12065 -0.305054)
			(stroke
				(width 0.1)
				(type default)
			)
			(layer "F.Fab")
		)
		(fp_line
			(start 0.67945 -0.3048)
			(end 0.67945 0.3048)
			(stroke
				(width 0.1)
				(type default)
			)
			(layer "F.Fab")
		)
		(fp_line
			(start 0.12065 -0.3048)
			(end 0.67945 -0.3048)
			(stroke
				(width 0.1)
				(type default)
			)
			(layer "F.Fab")
		)
		(fp_line
			(start 0.12065 -0.2794)
			(end 0.12065 -0.3048)
			(stroke
				(width 0.1)
				(type default)
			)
			(layer "F.Fab")
		)
		(fp_line
			(start -0.12065 -0.2794)
			(end 0.12065 -0.2794)
			(stroke
				(width 0.1)
				(type default)
			)
			(layer "F.Fab")
		)
		(fp_line
			(start 0.120396 0.2794)
			(end -0.12065 0.2794)
			(stroke
				(width 0.1)
				(type default)
			)
			(layer "F.Fab")
		)
		(fp_line
			(start -0.12065 0.2794)
			(end -0.12065 0.3048)
			(stroke
				(width 0.1)
				(type default)
			)
			(layer "F.Fab")
		)
		(fp_line
			(start 0.67945 0.3048)
			(end 0.120396 0.3048)
			(stroke
				(width 0.1)
				(type default)
			)
			(layer "F.Fab")
		)
		(fp_line
			(start 0.120396 0.3048)
			(end 0.120396 0.2794)
			(stroke
				(width 0.1)
				(type default)
			)
			(layer "F.Fab")
		)
		(fp_line
			(start -0.12065 0.3048)
			(end -0.67945 0.3048)
			(stroke
				(width 0.1)
				(type default)
			)
			(layer "F.Fab")
		)
		(fp_line
			(start -0.67945 0.3048)
			(end -0.67945 -0.305054)
			(stroke
				(width 0.1)
				(type default)
			)
			(layer "F.Fab")
		)
		(pad "1" smd circle
			(at -0.40005 0 90)
			(size 0 0)
			(layers "F.Cu" "F.Mask" "F.Paste")
			(net "P12V_NIC7_CO_FLTB")
		)
		(pad "2" smd circle
			(at 0.40005 0 90)
			(size 0 0)
			(layers "F.Cu" "F.Mask" "F.Paste")
			(net "P3V3_AUX")
		)
	)
	(footprint ""
		(layer "F.Cu")
		(at 162.5346 -34.546286 180)
		(property "Reference" "C284"
			(at 0 0 180)
			(layer "F.SilkS")
			(hide yes)
			(effects
				(font
					(size 1.27 1.27)
				)
			)
		)
		(property "Value" ""
			(at 0 0 180)
			(layer "F.Fab")
			(effects
				(font
					(size 1.27 1.27)
				)
			)
		)
		(duplicate_pad_numbers_are_jumpers no)
		(fp_line
			(start 0.299974 0.150114)
			(end -0.299974 0.150114)
			(stroke
				(width 0.1)
				(type default)
			)
			(layer "F.Fab")
		)
		(fp_line
			(start 0.299974 -0.150114)
			(end 0.299974 0.150114)
			(stroke
				(width 0.1)
				(type default)
			)
			(layer "F.Fab")
		)
		(fp_line
			(start -0.299974 0.150114)
			(end -0.299974 -0.150114)
			(stroke
				(width 0.1)
				(type default)
			)
			(layer "F.Fab")
		)
		(fp_line
			(start -0.299974 -0.150114)
			(end 0.299974 -0.150114)
			(stroke
				(width 0.1)
				(type default)
			)
			(layer "F.Fab")
		)
		(pad "1" smd rect
			(at -0.2667 0 180)
			(size 0.3048 0.381)
			(layers "F.Cu" "F.Mask" "F.Paste")
			(net "P5E_PEX1_STN2_TX_DP<43>")
		)
		(pad "2" smd rect
			(at 0.2667 0 180)
			(size 0.3048 0.381)
			(layers "F.Cu" "F.Mask" "F.Paste")
			(net "P5E_PEX1_STN2_TX_C_DP<43>")
		)
	)
	(footprint ""
		(layer "F.Cu")
		(at 219.615512 -231.416606 -90)
		(property "Reference" "R4549"
			(at 0 0 270)
			(layer "F.SilkS")
			(hide yes)
			(effects
				(font
					(size 1.27 1.27)
				)
			)
		)
		(property "Value" ""
			(at 0 0 270)
			(layer "F.Fab")
			(effects
				(font
					(size 1.27 1.27)
				)
			)
		)
		(duplicate_pad_numbers_are_jumpers no)
		(fp_line
			(start -0.7874 0.4064)
			(end -0.7874 -0.4064)
			(stroke
				(width 0.1524)
				(type default)
			)
			(layer "F.SilkS")
		)
		(fp_line
			(start 0.7874 0.4064)
			(end -0.7874 0.4064)
			(stroke
				(width 0.1524)
				(type default)
			)
			(layer "F.SilkS")
		)
		(fp_line
			(start -0.7874 -0.4064)
			(end 0.7874 -0.4064)
			(stroke
				(width 0.1524)
				(type default)
			)
			(layer "F.SilkS")
		)
		(fp_line
			(start 0.7874 -0.4064)
			(end 0.7874 0.4064)
			(stroke
				(width 0.1524)
				(type default)
			)
			(layer "F.SilkS")
		)
		(fp_line
			(start -0.67945 0.3048)
			(end -0.67945 -0.305054)
			(stroke
				(width 0.1)
				(type default)
			)
			(layer "F.Fab")
		)
		(fp_line
			(start -0.12065 0.3048)
			(end -0.67945 0.3048)
			(stroke
				(width 0.1)
				(type default)
			)
			(layer "F.Fab")
		)
		(fp_line
			(start 0.120396 0.3048)
			(end 0.120396 0.2794)
			(stroke
				(width 0.1)
				(type default)
			)
			(layer "F.Fab")
		)
		(fp_line
			(start 0.67945 0.3048)
			(end 0.120396 0.3048)
			(stroke
				(width 0.1)
				(type default)
			)
			(layer "F.Fab")
		)
		(fp_line
			(start -0.12065 0.2794)
			(end -0.12065 0.3048)
			(stroke
				(width 0.1)
				(type default)
			)
			(layer "F.Fab")
		)
		(fp_line
			(start 0.120396 0.2794)
			(end -0.12065 0.2794)
			(stroke
				(width 0.1)
				(type default)
			)
			(layer "F.Fab")
		)
		(fp_line
			(start -0.12065 -0.2794)
			(end 0.12065 -0.2794)
			(stroke
				(width 0.1)
				(type default)
			)
			(layer "F.Fab")
		)
		(fp_line
			(start 0.12065 -0.2794)
			(end 0.12065 -0.3048)
			(stroke
				(width 0.1)
				(type default)
			)
			(layer "F.Fab")
		)
		(fp_line
			(start 0.12065 -0.3048)
			(end 0.67945 -0.3048)
			(stroke
				(width 0.1)
				(type default)
			)
			(layer "F.Fab")
		)
		(fp_line
			(start 0.67945 -0.3048)
			(end 0.67945 0.3048)
			(stroke
				(width 0.1)
				(type default)
			)
			(layer "F.Fab")
		)
		(fp_line
			(start -0.67945 -0.305054)
			(end -0.12065 -0.305054)
			(stroke
				(width 0.1)
				(type default)
			)
			(layer "F.Fab")
		)
		(fp_line
			(start -0.12065 -0.305054)
			(end -0.12065 -0.2794)
			(stroke
				(width 0.1)
				(type default)
			)
			(layer "F.Fab")
		)
		(pad "1" smd circle
			(at -0.40005 0 270)
			(size 0 0)
			(layers "F.Cu" "F.Mask" "F.Paste")
			(net "GND")
		)
		(pad "2" smd circle
			(at 0.40005 0 270)
			(size 0 0)
			(layers "F.Cu" "F.Mask" "F.Paste")
			(net "REV_ID2")
		)
	)
	(footprint ""
		(layer "F.Cu")
		(at 26.243788 -43.85691)
		(property "Reference" "R510"
			(at 0 0 0)
			(layer "F.SilkS")
			(hide yes)
			(effects
				(font
					(size 1.27 1.27)
				)
			)
		)
		(property "Value" ""
			(at 0 0 0)
			(layer "F.Fab")
			(effects
				(font
					(size 1.27 1.27)
				)
			)
		)
		(duplicate_pad_numbers_are_jumpers no)
		(fp_line
			(start -0.7874 -0.4064)
			(end 0.7874 -0.4064)
			(stroke
				(width 0.1524)
				(type default)
			)
			(layer "F.SilkS")
		)
		(fp_line
			(start -0.7874 0.4064)
			(end -0.7874 -0.4064)
			(stroke
				(width 0.1524)
				(type default)
			)
			(layer "F.SilkS")
		)
		(fp_line
			(start 0.7874 -0.4064)
			(end 0.7874 0.4064)
			(stroke
				(width 0.1524)
				(type default)
			)
			(layer "F.SilkS")
		)
		(fp_line
			(start 0.7874 0.4064)
			(end -0.7874 0.4064)
			(stroke
				(width 0.1524)
				(type default)
			)
			(layer "F.SilkS")
		)
		(fp_line
			(start -0.67945 -0.305054)
			(end -0.12065 -0.305054)
			(stroke
				(width 0.1)
				(type default)
			)
			(layer "F.Fab")
		)
		(fp_line
			(start -0.67945 0.3048)
			(end -0.67945 -0.305054)
			(stroke
				(width 0.1)
				(type default)
			)
			(layer "F.Fab")
		)
		(fp_line
			(start -0.12065 -0.305054)
			(end -0.12065 -0.2794)
			(stroke
				(width 0.1)
				(type default)
			)
			(layer "F.Fab")
		)
		(fp_line
			(start -0.12065 -0.2794)
			(end 0.12065 -0.2794)
			(stroke
				(width 0.1)
				(type default)
			)
			(layer "F.Fab")
		)
		(fp_line
			(start -0.12065 0.2794)
			(end -0.12065 0.3048)
			(stroke
				(width 0.1)
				(type default)
			)
			(layer "F.Fab")
		)
		(fp_line
			(start -0.12065 0.3048)
			(end -0.67945 0.3048)
			(stroke
				(width 0.1)
				(type default)
			)
			(layer "F.Fab")
		)
		(fp_line
			(start 0.120396 0.2794)
			(end -0.12065 0.2794)
			(stroke
				(width 0.1)
				(type default)
			)
			(layer "F.Fab")
		)
		(fp_line
			(start 0.120396 0.3048)
			(end 0.120396 0.2794)
			(stroke
				(width 0.1)
				(type default)
			)
			(layer "F.Fab")
		)
		(fp_line
			(start 0.12065 -0.3048)
			(end 0.67945 -0.3048)
			(stroke
				(width 0.1)
				(type default)
			)
			(layer "F.Fab")
		)
		(fp_line
			(start 0.12065 -0.2794)
			(end 0.12065 -0.3048)
			(stroke
				(width 0.1)
				(type default)
			)
			(layer "F.Fab")
		)
		(fp_line
			(start 0.67945 -0.3048)
			(end 0.67945 0.3048)
			(stroke
				(width 0.1)
				(type default)
			)
			(layer "F.Fab")
		)
		(fp_line
			(start 0.67945 0.3048)
			(end 0.120396 0.3048)
			(stroke
				(width 0.1)
				(type default)
			)
			(layer "F.Fab")
		)
		(pad "1" smd circle
			(at -0.40005 0)
			(size 0 0)
			(layers "F.Cu" "F.Mask" "F.Paste")
			(net "SSD0_ADC_A1")
		)
		(pad "2" smd circle
			(at 0.40005 0)
			(size 0 0)
			(layers "F.Cu" "F.Mask" "F.Paste")
			(net "GND")
		)
	)
	(footprint ""
		(layer "F.Cu")
		(at 359.534206 -137.01776 180)
		(property "Reference" "PU27"
			(at 2.610358 -2.85369 0)
			(unlocked yes)
			(layer "F.SilkS")
			(effects
				(font
					(size 0.7874 0.5842)
					(thickness 0.1524)
				)
				(justify left)
			)
		)
		(property "Value" ""
			(at 0 0 180)
			(layer "F.Fab")
			(effects
				(font
					(size 1.27 1.27)
				)
			)
		)
		(duplicate_pad_numbers_are_jumpers no)
		(fp_line
			(start 1.943608 1.549908)
			(end -1.943608 1.549908)
			(stroke
				(width 0.1524)
				(type default)
			)
			(layer "F.SilkS")
		)
		(fp_line
			(start 1.943608 -1.549908)
			(end 1.943608 1.549908)
			(stroke
				(width 0.1524)
				(type default)
			)
			(layer "F.SilkS")
		)
		(fp_line
			(start -1.943608 1.549908)
			(end -1.943608 -1.549908)
			(stroke
				(width 0.1524)
				(type default)
			)
			(layer "F.SilkS")
		)
		(fp_line
			(start -1.943608 -1.549908)
			(end 1.943608 -1.549908)
			(stroke
				(width 0.1524)
				(type default)
			)
			(layer "F.SilkS")
		)
		(fp_poly
			(pts
				(xy -2.019808 -1.549908) (xy -1.257808 -1.549908) (xy -1.257808 -1.880108) (xy -2.019808 -1.880108)
			)
			(stroke
				(width 0)
				(type default)
			)
			(fill yes)
			(layer "F.SilkS")
		)
		(fp_line
			(start 1.549908 1.549908)
			(end -1.549908 1.549908)
			(stroke
				(width 0.1)
				(type default)
			)
			(layer "F.Fab")
		)
		(fp_line
			(start 1.549908 -1.549908)
			(end 1.549908 1.549908)
			(stroke
				(width 0.1)
				(type default)
			)
			(layer "F.Fab")
		)
		(fp_line
			(start -1.549908 1.549908)
			(end -1.549908 -1.549908)
			(stroke
				(width 0.1)
				(type default)
			)
			(layer "F.Fab")
		)
		(fp_line
			(start -1.549908 -1.549908)
			(end 1.549908 -1.549908)
			(stroke
				(width 0.1)
				(type default)
			)
			(layer "F.Fab")
		)
		(fp_poly
			(pts
				(xy -2.019808 -1.549908) (xy -1.257808 -1.549908) (xy -1.257808 -1.880108) (xy -2.019808 -1.880108)
			)
			(stroke
				(width 0)
				(type default)
			)
			(fill yes)
			(layer "F.Fab")
		)
		(pad "1" smd rect
			(at -1.500124 -1.249934 90)
			(size 0.2794 0.6096)
			(layers "F.Cu" "F.Mask" "F.Paste")
			(net "P12V_NIC6_R")
		)
		(pad "2" smd rect
			(at -1.500124 -0.750062 90)
			(size 0.2794 0.6096)
			(layers "F.Cu" "F.Mask" "F.Paste")
			(net "P12V_NIC6_R")
		)
		(pad "3" smd rect
			(at -1.500124 -0.249936 90)
			(size 0.2794 0.6096)
			(layers "F.Cu" "F.Mask" "F.Paste")
			(net "P12V_NIC6_R")
		)
		(pad "4" smd rect
			(at -1.500124 0.249936 90)
			(size 0.2794 0.6096)
			(layers "F.Cu" "F.Mask" "F.Paste")
			(net "P12V_NIC6_R")
		)
		(pad "5" smd rect
			(at -1.500124 0.750062 90)
			(size 0.2794 0.6096)
			(layers "F.Cu" "F.Mask" "F.Paste")
			(net "P12V_NIC6_R")
		)
		(pad "6" smd rect
			(at -1.500124 1.249934 90)
			(size 0.2794 0.6096)
			(layers "F.Cu" "F.Mask" "F.Paste")
			(net "GND")
		)
		(pad "7" smd rect
			(at 1.500124 1.249934 90)
			(size 0.2794 0.6096)
			(layers "F.Cu" "F.Mask" "F.Paste")
			(net "P12V_NIC6_SS")
		)
		(pad "8" smd rect
			(at 1.500124 0.750062 90)
			(size 0.2794 0.6096)
			(layers "F.Cu" "F.Mask" "F.Paste")
			(net "PWRGD_P12V_NIC6")
		)
		(pad "9" smd rect
			(at 1.500124 0.249936 90)
			(size 0.2794 0.6096)
			(layers "F.Cu" "F.Mask" "F.Paste")
			(net "P12V_NIC6_OCP")
		)
		(pad "10" smd rect
			(at 1.500124 -0.249936 90)
			(size 0.2794 0.6096)
			(layers "F.Cu" "F.Mask" "F.Paste")
			(net "P5V_AUX")
		)
		(pad "11" smd rect
			(at 1.500124 -0.750062 90)
			(size 0.2794 0.6096)
			(layers "F.Cu" "F.Mask" "F.Paste")
			(net "P12V_NIC6_EN_R")
		)
		(pad "12" smd rect
			(at 1.500124 -1.249934 90)
			(size 0.2794 0.6096)
			(layers "F.Cu" "F.Mask" "F.Paste")
			(net "P12V_AUX")
		)
		(pad "13" smd rect
			(at 0 0 180)
			(size 1.9812 2.7178)
			(layers "F.Cu" "F.Mask" "F.Paste")
			(net "P12V_AUX")
		)
		(zone
			(layer "F.Cu")
			(hatch none 0.5)
			(connect_pads
				(clearance 0)
			)
			(min_thickness 0.25)
			(keepout
				(tracks not_allowed)
				(vias allowed)
				(pads allowed)
				(copperpour not_allowed)
				(footprints allowed)
			)
			(placement
				(enabled no)
				(sheetname "")
			)
			(fill
				(thermal_gap 0.5)
				(thermal_bridge_width 0.5)
				(island_removal_mode 0)
			)
			(polygon
				(pts
					(xy 358.391206 -135.46836) (xy 358.391206 -135.59536) (xy 358.391206 -138.56716) (xy 358.391206 -138.567668)
					(xy 360.677206 -138.567668) (xy 360.677206 -138.56716) (xy 360.677206 -138.44016) (xy 360.677206 -137.01776)
					(xy 360.575606 -137.01776) (xy 360.575606 -138.44016) (xy 358.492806 -138.44016) (xy 358.492806 -135.59536)
					(xy 360.575606 -135.59536) (xy 360.575606 -136.99236) (xy 360.677206 -136.99236) (xy 360.677206 -135.59536)
					(xy 360.677206 -135.46836) (xy 360.677206 -135.467852) (xy 358.391206 -135.467852)
				)
			)
		)
	)
	(footprint ""
		(layer "F.Cu")
		(at 38.599872 -150.263352 180)
		(property "Reference" "R15"
			(at 0 0 180)
			(layer "F.SilkS")
			(hide yes)
			(effects
				(font
					(size 1.27 1.27)
				)
			)
		)
		(property "Value" ""
			(at 0 0 180)
			(layer "F.Fab")
			(effects
				(font
					(size 1.27 1.27)
				)
			)
		)
		(duplicate_pad_numbers_are_jumpers no)
		(fp_line
			(start 0.7874 0.4064)
			(end -0.7874 0.4064)
			(stroke
				(width 0.1524)
				(type default)
			)
			(layer "F.SilkS")
		)
		(fp_line
			(start 0.7874 -0.4064)
			(end 0.7874 0.4064)
			(stroke
				(width 0.1524)
				(type default)
			)
			(layer "F.SilkS")
		)
		(fp_line
			(start -0.7874 0.4064)
			(end -0.7874 -0.4064)
			(stroke
				(width 0.1524)
				(type default)
			)
			(layer "F.SilkS")
		)
		(fp_line
			(start -0.7874 -0.4064)
			(end 0.7874 -0.4064)
			(stroke
				(width 0.1524)
				(type default)
			)
			(layer "F.SilkS")
		)
		(fp_line
			(start 0.67945 0.3048)
			(end 0.120396 0.3048)
			(stroke
				(width 0.1)
				(type default)
			)
			(layer "F.Fab")
		)
		(fp_line
			(start 0.67945 -0.3048)
			(end 0.67945 0.3048)
			(stroke
				(width 0.1)
				(type default)
			)
			(layer "F.Fab")
		)
		(fp_line
			(start 0.12065 -0.2794)
			(end 0.12065 -0.3048)
			(stroke
				(width 0.1)
				(type default)
			)
			(layer "F.Fab")
		)
		(fp_line
			(start 0.12065 -0.3048)
			(end 0.67945 -0.3048)
			(stroke
				(width 0.1)
				(type default)
			)
			(layer "F.Fab")
		)
		(fp_line
			(start 0.120396 0.3048)
			(end 0.120396 0.2794)
			(stroke
				(width 0.1)
				(type default)
			)
			(layer "F.Fab")
		)
		(fp_line
			(start 0.120396 0.2794)
			(end -0.12065 0.2794)
			(stroke
				(width 0.1)
				(type default)
			)
			(layer "F.Fab")
		)
		(fp_line
			(start -0.12065 0.3048)
			(end -0.67945 0.3048)
			(stroke
				(width 0.1)
				(type default)
			)
			(layer "F.Fab")
		)
		(fp_line
			(start -0.12065 0.2794)
			(end -0.12065 0.3048)
			(stroke
				(width 0.1)
				(type default)
			)
			(layer "F.Fab")
		)
		(fp_line
			(start -0.12065 -0.2794)
			(end 0.12065 -0.2794)
			(stroke
				(width 0.1)
				(type default)
			)
			(layer "F.Fab")
		)
		(fp_line
			(start -0.12065 -0.305054)
			(end -0.12065 -0.2794)
			(stroke
				(width 0.1)
				(type default)
			)
			(layer "F.Fab")
		)
		(fp_line
			(start -0.67945 0.3048)
			(end -0.67945 -0.305054)
			(stroke
				(width 0.1)
				(type default)
			)
			(layer "F.Fab")
		)
		(fp_line
			(start -0.67945 -0.305054)
			(end -0.12065 -0.305054)
			(stroke
				(width 0.1)
				(type default)
			)
			(layer "F.Fab")
		)
		(pad "1" smd circle
			(at -0.40005 0 180)
			(size 0 0)
			(layers "F.Cu" "F.Mask" "F.Paste")
			(net "NCSI_NIC0_CRS_DV")
		)
		(pad "2" smd circle
			(at 0.40005 0 180)
			(size 0 0)
			(layers "F.Cu" "F.Mask" "F.Paste")
			(net "GND")
		)
	)
)
